(kicad_pcb
	(version 20241229)
	(generator "pcbnew")
	(generator_version "9.0")
	(general
		(thickness 1.63)
		(legacy_teardrops no)
	)
	(paper "A4")
	(title_block
		(title "CM4 Baseboard")
		(date "2026-01-05")
		(rev "1.1.1")
		(company "Antmicro Ltd")
		(comment 1 "www.antmicro.com")
		(comment 9 "footprints 233-235 of 506")
	)
	(layers
		(0 "F.Cu" signal)
		(4 "In1.Cu" power)
		(6 "In2.Cu" power)
		(8 "In3.Cu" signal)
		(10 "In4.Cu" signal)
		(2 "B.Cu" signal)
		(9 "F.Adhes" user "F.Adhesive")
		(11 "B.Adhes" user "B.Adhesive")
		(13 "F.Paste" user)
		(15 "B.Paste" user)
		(5 "F.SilkS" user "F.Silkscreen")
		(7 "B.SilkS" user "B.Silkscreen")
		(1 "F.Mask" user)
		(3 "B.Mask" user)
		(17 "Dwgs.User" user "User.Drawings")
		(19 "Cmts.User" user "User.Comments")
		(21 "Eco1.User" user "User.Eco1")
		(23 "Eco2.User" user "User.Eco2")
		(25 "Edge.Cuts" user)
		(27 "Margin" user)
		(31 "F.CrtYd" user "F.Courtyard")
		(29 "B.CrtYd" user "B.Courtyard")
		(35 "F.Fab" user)
		(33 "B.Fab" user)
	)
	(footprint "antmicro-footprints:C_0402_1005Metric"
		(layer "F.Cu")
		(at 93.117962 144.7165 -90)
		(descr "Capacitor SMD 0402")
		(tags "capacitor SMD 0402")
		(property "Reference" "C925"
			(at -0.8165 -2.25 180)
			(layer "F.SilkS")
			(effects
				(font
					(size 0.7 0.7)
					(thickness 0.15)
				)
				(justify right bottom)
			)
		)
		(property "Value" "C_4u7_0402"
			(at -1.022927 2.155213 90)
			(layer "F.Fab")
			(effects
				(font
					(size 0.7 0.7)
					(thickness 0.15)
				)
				(justify right bottom)
			)
		)
		(property "Datasheet" "https://www.murata.com/products/productdetail?partno=GRM155R61A475MEAA%23"
			(at 0 0 270)
			(layer "F.Fab")
			(hide yes)
			(effects
				(font
					(size 1.27 1.27)
					(thickness 0.15)
				)
			)
		)
		(property "Manufacturer" "Murata"
			(at 0 0 270)
			(unlocked yes)
			(layer "F.Fab")
			(hide yes)
			(effects
				(font
					(size 1 1)
					(thickness 0.15)
				)
			)
		)
		(property "MPN" "GRM155R61A475MEAAD"
			(at 0 0 270)
			(unlocked yes)
			(layer "F.Fab")
			(hide yes)
			(effects
				(font
					(size 1 1)
					(thickness 0.15)
				)
			)
		)
		(property "Val" "4u7"
			(at 0 0 270)
			(unlocked yes)
			(layer "F.Fab")
			(hide yes)
			(effects
				(font
					(size 1 1)
					(thickness 0.15)
				)
			)
		)
		(property "License" "Apache-2.0"
			(at 0 0 270)
			(unlocked yes)
			(layer "F.Fab")
			(hide yes)
			(effects
				(font
					(size 1 1)
					(thickness 0.15)
				)
			)
		)
		(property "Author" "Antmicro"
			(at 0 0 270)
			(unlocked yes)
			(layer "F.Fab")
			(hide yes)
			(effects
				(font
					(size 1 1)
					(thickness 0.15)
				)
			)
		)
		(property "Voltage" ""
			(at 0 0 270)
			(unlocked yes)
			(layer "F.Fab")
			(hide yes)
			(effects
				(font
					(size 1 1)
					(thickness 0.15)
				)
			)
		)
		(property "Dielectric" ""
			(at 0 0 270)
			(unlocked yes)
			(layer "F.Fab")
			(hide yes)
			(effects
				(font
					(size 1 1)
					(thickness 0.15)
				)
			)
		)
		(sheetname "/USB/")
		(sheetfile "usb.kicad_sch")
		(attr smd)
		(fp_rect
			(start -0.925 -0.47)
			(end 0.925 0.47)
			(stroke
				(width 0.05)
				(type default)
			)
			(fill no)
			(layer "F.CrtYd")
		)
		(fp_line
			(start -0.494 0.248)
			(end -0.494 -0.25)
			(stroke
				(width 0.15)
				(type solid)
			)
			(layer "F.Fab")
		)
		(fp_line
			(start 0.504 0.248)
			(end -0.494 0.248)
			(stroke
				(width 0.15)
				(type solid)
			)
			(layer "F.Fab")
		)
		(fp_line
			(start -0.494 -0.25)
			(end 0.504 -0.25)
			(stroke
				(width 0.15)
				(type solid)
			)
			(layer "F.Fab")
		)
		(fp_line
			(start 0.504 -0.25)
			(end 0.504 0.248)
			(stroke
				(width 0.15)
				(type solid)
			)
			(layer "F.Fab")
		)
		(fp_text user "License: Apache-2.0"
			(at -0.939 5.799 270)
			(layer "F.Fab")
			(effects
				(font
					(size 0.7 0.7)
					(thickness 0.15)
				)
				(justify left bottom)
			)
		)
		(fp_text user "${REFERENCE}"
			(at -0.939 4.599 270)
			(layer "F.Fab")
			(effects
				(font
					(size 0.7 0.7)
					(thickness 0.15)
				)
				(justify left bottom)
			)
		)
		(fp_text user "Author: Antmicro"
			(at -0.939 3.399 270)
			(layer "F.Fab")
			(effects
				(font
					(size 0.7 0.7)
					(thickness 0.15)
				)
				(justify left bottom)
			)
		)
		(pad "1" smd roundrect
			(at -0.48 0 270)
			(size 0.59 0.64)
			(layers "F.Cu" "F.Mask" "F.Paste")
			(roundrect_rratio 0.25)
			(net 30 "/USB/USB_1V2")
			(pintype "passive")
		)
		(pad "2" smd roundrect
			(at 0.48 0 270)
			(size 0.59 0.64)
			(layers "F.Cu" "F.Mask" "F.Paste")
			(roundrect_rratio 0.25)
			(net 3 "GND")
			(pintype "passive")
		)
	)
	(footprint "antmicro-footprints:UQFN-12_2x1.7mm_P0.4mm_Texas_RUT"
		(layer "F.Cu")
		(at 85.367962 152.2465 90)
		(descr "Texas_R_PUQFN-N12")
		(tags "Texas_R_PUQFN-N12")
		(property "Reference" "U201"
			(at -1.92 -1.35 180)
			(layer "F.SilkS")
			(effects
				(font
					(size 0.7 0.7)
					(thickness 0.15)
				)
				(justify left bottom)
			)
		)
		(property "Value" "TXB0104_UQFN"
			(at 0 2.35 90)
			(layer "F.Fab")
			(effects
				(font
					(size 0.7 0.7)
					(thickness 0.15)
				)
				(justify left bottom)
			)
		)
		(property "Datasheet" "http://www.ti.com/lit/ds/symlink/txb0104.pdf"
			(at 0 0 90)
			(layer "F.Fab")
			(hide yes)
			(effects
				(font
					(size 1.27 1.27)
					(thickness 0.15)
				)
			)
		)
		(property "Manufacturer" "Texas Instruments"
			(at 0 0 90)
			(unlocked yes)
			(layer "F.Fab")
			(hide yes)
			(effects
				(font
					(size 1 1)
					(thickness 0.15)
				)
			)
		)
		(property "MPN" "TXB0104RUTR"
			(at 0 0 90)
			(unlocked yes)
			(layer "F.Fab")
			(hide yes)
			(effects
				(font
					(size 1 1)
					(thickness 0.15)
				)
			)
		)
		(property "Author" "Antmicro"
			(at 0 0 90)
			(unlocked yes)
			(layer "F.Fab")
			(hide yes)
			(effects
				(font
					(size 1 1)
					(thickness 0.15)
				)
			)
		)
		(property "License" "Apache-2.0"
			(at 0 0 90)
			(unlocked yes)
			(layer "F.Fab")
			(hide yes)
			(effects
				(font
					(size 1 1)
					(thickness 0.15)
				)
			)
		)
		(property ki_fp_filters "Texas*R*PUQFN*N12*")
		(sheetname "/Compute module/")
		(sheetfile "compute-module.kicad_sch")
		(attr smd)
		(fp_line
			(start 0.597 -1.301)
			(end -0.55 -1.301)
			(stroke
				(width 0.15)
				(type solid)
			)
			(layer "F.SilkS")
		)
		(fp_line
			(start 0.497 1.3)
			(end -0.5 1.3)
			(stroke
				(width 0.15)
				(type solid)
			)
			(layer "F.SilkS")
		)
		(fp_circle
			(center -0.85 -1.2)
			(end -0.8 -1.2)
			(stroke
				(width 0.15)
				(type solid)
			)
			(fill yes)
			(layer "F.SilkS")
		)
		(fp_rect
			(start -1.1 -1.3)
			(end 1.1 1.3)
			(stroke
				(width 0.05)
				(type solid)
			)
			(fill no)
			(layer "F.CrtYd")
		)
		(fp_line
			(start 0.847 -1)
			(end 0.847 0.997)
			(stroke
				(width 0.15)
				(type solid)
			)
			(layer "F.Fab")
		)
		(fp_line
			(start -0.5 -1)
			(end 0.847 -1)
			(stroke
				(width 0.15)
				(type solid)
			)
			(layer "F.Fab")
		)
		(fp_line
			(start -0.5 -1)
			(end -0.85 -0.5)
			(stroke
				(width 0.15)
				(type solid)
			)
			(layer "F.Fab")
		)
		(fp_line
			(start 0.847 0.997)
			(end -0.85 0.997)
			(stroke
				(width 0.15)
				(type solid)
			)
			(layer "F.Fab")
		)
		(fp_line
			(start -0.85 0.997)
			(end -0.85 -0.5)
			(stroke
				(width 0.15)
				(type solid)
			)
			(layer "F.Fab")
		)
		(fp_text user "License: Apache-2.0"
			(at -1.1 6.75 90)
			(layer "F.Fab")
			(effects
				(font
					(size 0.7 0.7)
					(thickness 0.15)
				)
				(justify left bottom)
			)
		)
		(fp_text user "${REFERENCE}"
			(at -1.1 5.55 90)
			(layer "F.Fab")
			(effects
				(font
					(size 0.7 0.7)
					(thickness 0.15)
				)
				(justify left bottom)
			)
		)
		(fp_text user "Author: Antmicro"
			(at -1.1 4.35 90)
			(layer "F.Fab")
			(effects
				(font
					(size 0.7 0.7)
					(thickness 0.15)
				)
				(justify left bottom)
			)
		)
		(pad "1" smd rect
			(at -0.653 -0.803)
			(size 0.2 0.6)
			(layers "F.Cu" "F.Mask" "F.Paste")
			(net 18 "V_{IO}")
			(pinfunction "VCCA")
			(pintype "power_in")
		)
		(pad "1" smd rect
			(at -0.425 -0.975 90)
			(size 0.15 0.25)
			(layers "F.Cu" "F.Mask" "F.Paste")
			(net 18 "V_{IO}")
			(pinfunction "VCCA")
			(pintype "power_in")
		)
		(pad "2" smd rect
			(at -0.653 -0.403)
			(size 0.2 0.6)
			(layers "F.Cu" "F.Mask" "F.Paste")
			(net 225 "/Compute module/GPIO.5{slash}RXD3")
			(pinfunction "A1")
			(pintype "tri_state")
		)
		(pad "3" smd rect
			(at -0.653 0)
			(size 0.2 0.6)
			(layers "F.Cu" "F.Mask" "F.Paste")
			(net 240 "/Compute module/GPIO.4{slash}TXD3")
			(pinfunction "A2")
			(pintype "tri_state")
		)
		(pad "4" smd rect
			(at -0.653 0.4)
			(size 0.2 0.6)
			(layers "F.Cu" "F.Mask" "F.Paste")
			(net 229 "/Compute module/GPIO.9{slash}RXD4")
			(pinfunction "A3")
			(pintype "tri_state")
		)
		(pad "5" smd rect
			(at -0.653 0.8)
			(size 0.2 0.6)
			(layers "F.Cu" "F.Mask" "F.Paste")
			(net 228 "/Compute module/GPIO.8{slash}TXD4")
			(pinfunction "A4")
			(pintype "tri_state")
		)
		(pad "6" smd rect
			(at 0 0.8)
			(size 0.6 0.2)
			(layers "F.Cu" "F.Mask" "F.Paste")
			(net 3 "GND")
			(pinfunction "GND")
			(pintype "power_in")
		)
		(pad "7" smd rect
			(at 0.65 0.8)
			(size 0.2 0.6)
			(layers "F.Cu" "F.Mask" "F.Paste")
			(net 188 "/Compute module/UART.2.TX")
			(pinfunction "B4")
			(pintype "tri_state")
		)
		(pad "8" smd rect
			(at 0.65 0.4)
			(size 0.2 0.6)
			(layers "F.Cu" "F.Mask" "F.Paste")
			(net 189 "/Compute module/UART.2.RX")
			(pinfunction "B3")
			(pintype "tri_state")
		)
		(pad "9" smd rect
			(at 0.65 0)
			(size 0.2 0.6)
			(layers "F.Cu" "F.Mask" "F.Paste")
			(net 190 "/Compute module/UART.3.TX")
			(pinfunction "B2")
			(pintype "tri_state")
		)
		(pad "10" smd rect
			(at 0.65 -0.403)
			(size 0.2 0.6)
			(layers "F.Cu" "F.Mask" "F.Paste")
			(net 191 "/Compute module/UART.3.RX")
			(pinfunction "B1")
			(pintype "tri_state")
		)
		(pad "11" smd rect
			(at 0.65 -0.803)
			(size 0.2 0.6)
			(layers "F.Cu" "F.Mask" "F.Paste")
			(net 9 "+3V3")
			(pinfunction "VCCB")
			(pintype "power_in")
		)
		(pad "12" smd rect
			(at 0 -0.803)
			(size 0.6 0.2)
			(layers "F.Cu" "F.Mask" "F.Paste")
			(net 18 "V_{IO}")
			(pinfunction "OE")
			(pintype "input")
		)
	)
	(footprint "antmicro-footprints:R_0402_1005Metric"
		(layer "F.Cu")
		(at 104.272962 128.3865)
		(descr "Resistor SMD 0402")
		(tags "resistor SMD 0402")
		(property "Reference" "R925"
			(at 0.97 0.38 0)
			(layer "F.SilkS")
			(effects
				(font
					(size 0.7 0.7)
					(thickness 0.15)
				)
				(justify left bottom)
			)
		)
		(property "Value" "R_100k_0402"
			(at -1.011843 1.772047 0)
			(layer "F.Fab")
			(effects
				(font
					(size 0.7 0.7)
					(thickness 0.15)
				)
				(justify left bottom)
			)
		)
		(property "Datasheet" "https://www.bourns.com/docs/product-datasheets/cr.pdf"
			(at 0 0 0)
			(layer "F.Fab")
			(hide yes)
			(effects
				(font
					(size 1.27 1.27)
					(thickness 0.15)
				)
			)
		)
		(property "Manufacturer" "Bourns"
			(at 0 0 0)
			(unlocked yes)
			(layer "F.Fab")
			(hide yes)
			(effects
				(font
					(size 1 1)
					(thickness 0.15)
				)
			)
		)
		(property "MPN" "CR0402-FX-1003GLF"
			(at 0 0 0)
			(unlocked yes)
			(layer "F.Fab")
			(hide yes)
			(effects
				(font
					(size 1 1)
					(thickness 0.15)
				)
			)
		)
		(property "Val" "100k"
			(at 0 0 0)
			(unlocked yes)
			(layer "F.Fab")
			(hide yes)
			(effects
				(font
					(size 1 1)
					(thickness 0.15)
				)
			)
		)
		(property "License" "Apache-2.0"
			(at 0 0 0)
			(unlocked yes)
			(layer "F.Fab")
			(hide yes)
			(effects
				(font
					(size 1 1)
					(thickness 0.15)
				)
			)
		)
		(property "Author" "Antmicro"
			(at 0 0 0)
			(unlocked yes)
			(layer "F.Fab")
			(hide yes)
			(effects
				(font
					(size 1 1)
					(thickness 0.15)
				)
			)
		)
		(property "Tolerance" "1%"
			(at 0 0 0)
			(unlocked yes)
			(layer "F.Fab")
			(hide yes)
			(effects
				(font
					(size 1 1)
					(thickness 0.15)
				)
			)
		)
		(sheetname "/USB/")
		(sheetfile "usb.kicad_sch")
		(attr smd)
		(fp_rect
			(start -0.925 -0.47)
			(end 0.925 0.47)
			(stroke
				(width 0.05)
				(type default)
			)
			(fill no)
			(layer "F.CrtYd")
		)
		(fp_rect
			(start -0.5 -0.25)
			(end 0.5 0.25)
			(stroke
				(width 0.15)
				(type solid)
			)
			(fill no)
			(layer "F.Fab")
		)
		(fp_text user "${REFERENCE}"
			(at -0.95 3.168 0)
			(layer "F.Fab")
			(effects
				(font
					(size 0.7 0.7)
					(thickness 0.15)
				)
				(justify left bottom)
			)
		)
		(fp_text user "License: Apache-2.0"
			(at -0.95 5.169 0)
			(layer "F.Fab")
			(effects
				(font
					(size 0.7 0.7)
					(thickness 0.15)
				)
				(justify left bottom)
			)
		)
		(fp_text user "Author: Antmicro"
			(at -0.95 4.169 0)
			(layer "F.Fab")
			(effects
				(font
					(size 0.7 0.7)
					(thickness 0.15)
				)
				(justify left bottom)
			)
		)
		(pad "1" smd roundrect
			(at -0.48 0)
			(size 0.59 0.64)
			(layers "F.Cu" "F.Mask" "F.Paste")
			(roundrect_rratio 0.25)
			(net 28 "/USB/+5V_{CAP}")
			(pintype "passive")
		)
		(pad "2" smd roundrect
			(at 0.48 0)
			(size 0.59 0.64)
			(layers "F.Cu" "F.Mask" "F.Paste")
			(roundrect_rratio 0.25)
			(net 3 "GND")
			(pintype "passive")
		)
	)
)
